FILE_TYPE = CONNECTIVITY;
{Allegro Design Entry HDL 16.6-p007 (v16-6-112F) 10/10/2012}
"PAGE_NUMBER" = 224;
0"NC";
1"PVDDQ_GHJ\g";
2"GND\g";
3"GND\g";
4"GND\g";
5"GND\g";
6"GND\g";
7"GND\g";
8"GND\g";
9"GND\g";
10"GND\g";
11"PVDDQ_GHJ\g";
12"GND\g";
13"GND\g";
14"GND\g";
15"VR_FET_SW_P12V_STBY_PVDDQ_GHJ\g";
16"GND\g";
17"P5V_STBY\g";
18"P5V_STBY\g";
19"VR_FET_SW_P12V_STBY_PVDDQ_GHJ\g";
20"TP_PVDDQ_GHJ_PH1_GL_0";
21"VR_PVDDQ_GHJ_PH2_VCIN";
22"VR_PVDDQ_GHJ_PWM2";
23"A_TSENSE_PVDDQ_GHJ";
24"VR_PVDDQ_GHJ_PH1_SW";
25"VR_PVDDQ_GHJ_PH1_SW_RC";
26"VR_PVDDQ_GHJ_PWM1";
27"TP_PVDDQ_GHJ_PH1_GL_1";
28"VR_PVDDQ_GHJ_AIREF1";
29"VR_PVDDQ_GHJ_PH1_VCIN";
30"ISENSE_PVDDQ_GHJ_PH1_IMON";
31"VR_PVDDQ_GHJ_PH1_OCSET"VOLTAGE"3.6";
32"VR_PVDDQ_GHJ_PH1_BOOT_R";
33"VR_PVDDQ_GHJ_PH2_PHASE";
34"VR_PVDDQ_GHJ_PH2_SW_RC";
35"VR_PVDDQ_GHJ_PH2_SW";
36"VR_PVDDQ_GHJ_AIREF2";
37"TP_PVDDQ_GHJ_PH2_GL_1";
38"VR_PVDDQ_GHJ_PH2_BOOT_R";
39"VR_PVDDQ_GHJ_PH2_BOOT";
40"TP_PVDDQ_GHJ_PH2_GL_0";
41"A_TSENSE_PVDDQ_GHJ";
42"VR_PVDDQ_GHJ_PH2_OCSET"VOLTAGE"3.6";
43"ISENSE_PVDDQ_GHJ_PH2_IMON";
44"VR_PVDDQ_GHJ_PH1_BOOT";
45"VR_PVDDQ_GHJ_PH1_PHASE";
46"GND\g";
%"PVDDQ_GHJ"
"1","(4500,2050)","0","mstr_symbols","I1";
;
VOLTAGE"1.2V"
CDS_LIB"mstr_symbols"
BODY_TYPE"PLUMBING"
HDL_POWER"PVDDQ_GHJ";
"G\NAC"1;
%"IR354XX"
"1","(1825,2250)","0","mstr_discrete","I110";
;
CDS_SEC"1"
PART_NUMBER"H73688-001"
NO_XNET_CONNECTION"1"
MATERIAL"IC"
LOCATION"EU1G1"
PACK_TYPE"SM"
SEC_TYPE"SM"
SEC"1"
CDS_LOCATION"EU1G1"
CDS_LIB"mstr_discrete"
VALUE"IR35411";
"TOUT_FLT"
$PN"36"23;
"NC"
$PN"31"0;
"OCSET"
$PN"37"31;
"IOUT"
$PN"38"30;
"SW"
$PN"10"24;
"BOOST"
$PN"33"32;
"REFIN"
$PN"39"28;
"PWM"
$PN"34"26;
"PHASE"
$PN"32"45;
"VIN<0>"
$PN"25"19;
"VCC"
$PN"3"29;
"VIN<1>"
$PN"30"19;
"EN"
$PN"35"17;
"VDRV"
$PN"4"17;
"VOS"
$PN"1"1;
"LGND"
$PN"2"9;
"PGND<1>"
$PN"7"9;
"PGND<2>"
$PN"40"9;
"PGND<0>"
$PN"5"9;
"GL<0>"
$PN"6"20;
"GL<1>"
$PN"41"27;
%"IR354XX"
"1","(1850,-125)","0","mstr_discrete","I111";
;
CDS_SEC"1"
BOM_SS"NOPOP"
MATERIAL"IC"
PART_NUMBER"H73688-001"
LOCATION"EU1F1"
PACK_TYPE"SM"
SEC_TYPE"SM"
SEC"1"
CDS_LOCATION"EU1F1"
CDS_LIB"mstr_discrete"
VALUE"IR35411";
"TOUT_FLT"
$PN"36"41;
"NC"
$PN"31"0;
"OCSET"
$PN"37"42;
"IOUT"
$PN"38"43;
"SW"
$PN"10"35;
"BOOST"
$PN"33"38;
"REFIN"
$PN"39"36;
"PWM"
$PN"34"22;
"PHASE"
$PN"32"33;
"VIN<0>"
$PN"25"15;
"VCC"
$PN"3"21;
"VIN<1>"
$PN"30"15;
"EN"
$PN"35"18;
"VDRV"
$PN"4"18;
"VOS"
$PN"1"11;
"LGND"
$PN"2"14;
"PGND<1>"
$PN"7"14;
"PGND<2>"
$PN"40"14;
"PGND<0>"
$PN"5"14;
"GL<0>"
$PN"6"40;
"GL<1>"
$PN"41"37;
%"RES"
"2","(4625,2400)","0","mstr_discrete","I112";
;
CDS_SEC"1"
CDS_LOCATION"R1G26"
VALUE"68.1K"
TOLERANCE"1%"
LOCATION"R1G26"
MATERIAL"EMPTY"
WATTAGE"1/16W"
PACK_TYPE"0402"
PART_NUMBER"G21796-187"
SEC_TYPE"0402"
SEC"1"
CDS_LIB"mstr_discrete";
"A"
$PN"1"31;
"B"
$PN"2"2;
%"GND"
"1","(4625,2225)","0","mstr_symbols","I113";
;
VOLTAGE"0"
CDS_LIB"mstr_symbols"
SIZE"1B"
BOM_COST"PROC_VRD_VCCIN_CPU0"
ROOM"PVCCIN_CPU0_PWR_VR"
BODY_TYPE"PLUMBING"
HDL_POWER"GND";
"A\NAC"2;
%"RES"
"2","(4650,25)","0","mstr_discrete","I114";
;
CDS_SEC"1"
CDS_LOCATION"R1G25"
PART_NUMBER"G21796-187"
VALUE"68.1K"
PACK_TYPE"0402"
LOCATION"R1G25"
BOM_SS"NOPOP"
TOLERANCE"1%"
WATTAGE"1/16W"
MATERIAL"EMPTY"
SEC_TYPE"0402"
SEC"1"
CDS_LIB"mstr_discrete";
"A"
$PN"1"42;
"B"
$PN"2"3;
%"GND"
"1","(4650,-150)","0","mstr_symbols","I115";
;
SIZE"1B"
VOLTAGE"0"
CDS_LIB"mstr_symbols"
BOM_COST"PROC_VRD_VCCIN_CPU0"
ROOM"PVCCIN_CPU0_PWR_VR"
BODY_TYPE"PLUMBING"
HDL_POWER"GND";
"A\NAC"3;
%"CAP_A"
"1","(1050,1725)","0","dev_discrete","I117";
;
CDS_SEC"1"
CDS_LOCATION"CT30"
LOCATION"CT30"
VOLTAGE"16V"
PART_NUMBER"A36096-030"
PACK_TYPE"0402V"
POP"NOPOP"
VALUE"0.1UF"
TOLERANCE"10%"
MATERIAL"X7R"
SEC_TYPE"0402V"
SEC"1"
CDS_LIB"dev_discrete"
ROOM"PVCCIN_CPU0_PWR_VR";
"B"
$PN"2"4;
"A"
$PN"1"28;
%"GND"
"1","(1050,1475)","0","mstr_symbols","I118";
;
CDS_LIB"mstr_symbols"
ROOM"PVCCIN_CPU0_PWR_VR"
BOM_COST"PROC_VRD_VCCIN_CPU0"
SIZE"1B"
VOLTAGE"0"
BODY_TYPE"PLUMBING"
HDL_POWER"GND";
"A\NAC"4;
%"GND"
"1","(2900,1250)","0","mstr_symbols","I120";
;
CDS_LIB"mstr_symbols"
ROOM"PVCCIN_CPU0_PWR_VR"
BOM_COST"PROC_VRD_VCCIN_CPU0"
VOLTAGE"0"
SIZE"1B"
BODY_TYPE"PLUMBING"
HDL_POWER"GND";
"A\NAC"5;
%"CAP"
"1","(2950,2225)","0","mstr_discrete","I122";
;
CDS_SEC"1"
CDS_LOCATION"CT28"
PACK_TYPE"0402LF"
VOLTAGE"50V"
MATERIAL"X7R"
TOLERANCE"10%"
PART_NUMBER"A36096-046"
LOCATION"CT28"
POP"NOPOP"
VALUE"1000PF"
SEC_TYPE"0402LF"
SEC"1"
CDS_LIB"mstr_discrete"
ROOM"VDDQ_KLM_PWR_VR";
"A"
$PN"1"23;
"B"
$PN"2"6;
%"GND"
"1","(2950,2025)","0","mstr_symbols","I123";
;
CDS_LIB"mstr_symbols"
ROOM"VDDQ_KLM_PWR_VR"
VOLTAGE"0"
SIZE"1B"
BODY_TYPE"PLUMBING"
HDL_POWER"GND";
"A\NAC"6;
%"CAP_A"
"1","(1150,-625)","0","dev_discrete","I124";
;
CDS_SEC"1"
CDS_LOCATION"CT31"
BOM_SS"NOPOP"
VOLTAGE"16V"
LOCATION"CT31"
PART_NUMBER"A36096-030"
PACK_TYPE"0402V"
POP"NOPOP"
MATERIAL"X7R"
TOLERANCE"10%"
VALUE"0.1UF"
SEC_TYPE"0402V"
SEC"1"
CDS_LIB"dev_discrete"
ROOM"PVCCIN_CPU0_PWR_VR";
"B"
$PN"2"7;
"A"
$PN"1"36;
%"GND"
"1","(1150,-875)","0","mstr_symbols","I125";
;
ROOM"PVCCIN_CPU0_PWR_VR"
BOM_COST"PROC_VRD_VCCIN_CPU0"
SIZE"1B"
VOLTAGE"0"
CDS_LIB"mstr_symbols"
BODY_TYPE"PLUMBING"
HDL_POWER"GND";
"A\NAC"7;
%"GND"
"1","(3250,-1100)","0","mstr_symbols","I128";
;
CDS_LIB"mstr_symbols"
ROOM"PVCCIN_CPU0_PWR_VR"
BOM_COST"PROC_VRD_VCCIN_CPU0"
VOLTAGE"0"
SIZE"1B"
BODY_TYPE"PLUMBING"
HDL_POWER"GND";
"A\NAC"46;
%"CAP"
"1","(3050,-75)","0","mstr_discrete","I130";
;
CDS_SEC"1"
CDS_LOCATION"CT32"
TOLERANCE"10%"
PACK_TYPE"0402LF"
PART_NUMBER"A36096-046"
MATERIAL"X7R"
BOM_SS"NOPOP"
VOLTAGE"50V"
LOCATION"CT32"
VALUE"1000PF"
POP"NOPOP"
SEC_TYPE"0402LF"
SEC"1"
CDS_LIB"mstr_discrete"
ROOM"VDDQ_KLM_PWR_VR";
"A"
$PN"1"41;
"B"
$PN"2"8;
%"GND"
"1","(3050,-300)","0","mstr_symbols","I131";
;
CDS_LIB"mstr_symbols"
ROOM"VDDQ_KLM_PWR_VR"
VOLTAGE"0"
SIZE"1B"
BODY_TYPE"PLUMBING"
HDL_POWER"GND";
"A\NAC"8;
%"CAP"
"1","(2900,1800)","0","mstr_discrete","I140";
;
CDS_SEC"1"
CDS_LOCATION"CT29"
POP"NOPOP"
PART_NUMBER"A36096-046"
MATERIAL"X7R"
VOLTAGE"50V"
PACK_TYPE"0402LF"
TOLERANCE"10%"
VALUE"1000PF"
LOCATION"CT29"
SEC_TYPE"0402LF"
SEC"1"
ROOM"VDDQ_KLM_PWR_VR"
CDS_LIB"mstr_discrete";
"A"
$PN"1"24;
"B"
$PN"2"25;
%"CAP"
"1","(3250,-625)","0","mstr_discrete","I141";
;
CDS_SEC"1"
CDS_LOCATION"CT33"
PACK_TYPE"0402LF"
MATERIAL"X7R"
TOLERANCE"10%"
VOLTAGE"50V"
VALUE"1000PF"
PART_NUMBER"A36096-046"
LOCATION"CT33"
POP"NOPOP"
BOM_SS"NOPOP"
SEC_TYPE"0402LF"
SEC"1"
CDS_LIB"mstr_discrete"
ROOM"VDDQ_KLM_PWR_VR";
"A"
$PN"1"35;
"B"
$PN"2"34;
%"RES"
"1","(100,2000)","0","mstr_discrete","I144";
;
CDS_SEC"1"
CDS_LOCATION"RT19"
PACK_TYPE"0603"
MATERIAL"CHIP"
LOCATION"RT19"
VALUE"0"
WATTAGE"1/10W"
TOLERANCE"5.0%"
PART_NUMBER"G22178-002"
SEC_TYPE"0603"
SEC"1"
ROOM"NIC_SPRV"
BOM_COST"NT_GBE_BASE"
CDS_LIB"mstr_discrete";
"B"
$PN"2"32;
"A"
$PN"1"44;
%"RES"
"1","(275,-325)","0","mstr_discrete","I145";
;
CDS_SEC"1"
CDS_LOCATION"RT21"
BOM_SS"NOPOP"
VALUE"0"
WATTAGE"1/10W"
PACK_TYPE"0603"
TOLERANCE"5.0%"
PART_NUMBER"G22178-002"
MATERIAL"CHIP"
LOCATION"RT21"
SEC_TYPE"0603"
SEC"1"
CDS_LIB"mstr_discrete"
BOM_COST"NT_GBE_BASE"
ROOM"NIC_SPRV";
"B"
$PN"2"38;
"A"
$PN"1"39;
%"RES"
"1","(-700,3050)","0","mstr_discrete","I150";
;
LOCATION"R9U1"
TOLERANCE"5%"
PACK_TYPE"0402"
WATTAGE"1/16W"
VALUE"0.0"
MATERIAL"CHIP"
PART_NUMBER"G21497-005"
CDS_LOCATION"R9U1"
CDS_SEC"1"
ROOM"CPU0"
SEC"1"
SEC_TYPE"0402"
CDS_LIB"mstr_discrete"
BOM_COST"PROC_SIDEBAND";
"B"
$PN"2"17;
"A"
$PN"1"29;
%"RES"
"1","(-550,675)","0","mstr_discrete","I151";
;
PART_NUMBER"G21497-005"
PACK_TYPE"0402"
VALUE"0.0"
TOLERANCE"5%"
LOCATION"R9U12"
BOM_SS"NOPOP"
MATERIAL"CHIP"
WATTAGE"1/16W"
CDS_LOCATION"R9U12"
CDS_SEC"1"
ROOM"CPU0"
SEC"1"
SEC_TYPE"0402"
CDS_LIB"mstr_discrete"
BOM_COST"PROC_SIDEBAND";
"B"
$PN"2"18;
"A"
$PN"1"21;
%"SC1U10V2KX-4-GP"
"1","(-250,150)","0","w_hdl","I154";
;
CDS_SEC"1"
CDS_LOCATION"C1F21"
BOM_SS"NOPOP"
PACK_SIZE"0402"
VALUE"SC1U10V2KX-4-GP"
RATED"10V"
TOLERANCE"10%"
ATTRIBUTE"1UF"
LOCATION"C1F21"
PACK_TYPE"SMD-BCG6"
SEC"1"
SEC_TYPE"SMD-BCG6"
PART_NUMBER"78.10523.8FL"
CDS_LIB"w_hdl"
CDS_LMAN_SYM_OUTLINE"-50,25,50,-25";
"2"
$PN"2"16;
"1"
$PN"1"18;
%"SC1U10V2KX-4-GP"
"1","(-375,2500)","0","w_hdl","I155";
;
CDS_SEC"1"
CDS_LOCATION"C1G4"
PACK_SIZE"0402"
RATED"10V"
TOLERANCE"10%"
ATTRIBUTE"1UF"
VALUE"SC1U10V2KX-4-GP"
LOCATION"C1G4"
PACK_TYPE"SMD-BCG6"
SEC"1"
SEC_TYPE"SMD-BCG6"
CDS_LMAN_SYM_OUTLINE"-50,25,50,-25"
CDS_LIB"w_hdl"
PART_NUMBER"78.10523.8FL";
"2"
$PN"2"10;
"1"
$PN"1"17;
%"1R3F-GP"
"1","(2900,1475)","0","w_hdl","I156";
;
CDS_SEC"1"
CDS_LOCATION"RT20"
TOLERANCE"1%"
ATTRIBUTE"1 OHM"
VALUE"1R3F-GP"
LOCATION"RT20"
RATED"1/10W"
PACK_SIZE"0603"
POP"NOPOP"
CDS_LMAN_SYM_OUTLINE"-50,75,50,-75"
CDS_LIB"w_hdl"
PART_NUMBER"64.1R005.55L"
SEC_TYPE"RCL_GP"
SEC"1"
PACK_TYPE"RCL_GP";
"2"
$PN"2"5;
"1"
$PN"1"25;
%"1R3F-GP"
"1","(3250,-925)","0","w_hdl","I157";
;
CDS_SEC"1"
CDS_LOCATION"RT22"
TOLERANCE"1%"
ATTRIBUTE"1 OHM"
VALUE"1R3F-GP"
LOCATION"RT22"
RATED"1/10W"
BOM_SS"NOPOP"
PACK_SIZE"0603"
POP"NOPOP"
CDS_LMAN_SYM_OUTLINE"-50,75,50,-75"
CDS_LIB"w_hdl"
PART_NUMBER"64.1R005.55L"
SEC_TYPE"RCL_GP"
SEC"1"
PACK_TYPE"RCL_GP";
"2"
$PN"2"46;
"1"
$PN"1"34;
%"IND-120NH-30-GP"
"1","(3950,1975)","1","w_hdl","I160";
;
CDS_SEC"1"
CDS_LOCATION"L1G1"
LOCATION"L1G1"
NEW_RATED"DS_ISAT=134A@25C"
DS_VALUE"90NH"
BOM_DS"068.9002N.1021"
SS_ISAT"94A@25C"
SS_VALUE"120NH"
BOM_SS"068.1202N.M001"
NEW_PACK_SIZE"DCR=0.17MOHM"
NEW_TYPE"IRMS=66A@DELTA_T<40C"
PART_NUMBER"068.1202N.M001"
CDS_LIB"w_hdl"
CDS_LMAN_SYM_OUTLINE"-75,100,75,-100"
SEC_TYPE"DISCRET-GB2"
SEC"1"
PACK_TYPE"DISCRET-GB2"
VALUE"IND-120NH-30-GP"
ATTRIBUTE"120NH"
RATED"ISAT=94A@25C"
PACK_SIZE"DCR=0.17MOHM"
TYPE"IRMS=66A@DELTA_T<40C";
"F"
$PN"2"1;
"S"
$PN"1"24;
%"IND-120NH-30-GP"
"1","(3900,-400)","1","w_hdl","I161";
;
CDS_SEC"1"
CDS_LOCATION"L1F2"
LOCATION"L1F2"
NEW_PACK_SIZE"DCR=0.17MOHM"
NEW_TYPE"IRMS=66A@DELTA_T<40C"
DS_VALUE"90NH"
BOM_DS"068.9002N.1021"
BOM_SS"NOPOP"
NEW_RATED"DS_ISAT=134A@25C"
PART_NUMBER"068.1202N.M001"
CDS_LIB"w_hdl"
CDS_LMAN_SYM_OUTLINE"-75,100,75,-100"
SEC_TYPE"DISCRET-GB2"
SEC"1"
PACK_TYPE"DISCRET-GB2"
VALUE"IND-120NH-30-GP"
ATTRIBUTE"120NH"
RATED"ISAT=94A@25C"
PACK_SIZE"DCR=0.17MOHM"
TYPE"IRMS=66A@DELTA_T<40C";
"F"
$PN"2"11;
"S"
$PN"1"35;
%"GND"
"1","(2675,1500)","0","mstr_symbols","I19";
;
CDS_LIB"mstr_symbols"
VOLTAGE"0"
SIZE"1B"
BOM_COST"VDDQ_GHJ_PWR_VR"
ROOM"VDDQ_GHJ_PWR_VR"
BODY_TYPE"PLUMBING"
HDL_POWER"GND";
"A\NAC"9;
%"GND"
"1","(-1950,2025)","0","mstr_symbols","I35";
;
CDS_LIB"mstr_symbols"
VOLTAGE"0"
BOM_COST"VDDQ_GHJ_PWR_VR"
ROOM"VDDQ_GHJ_PWR_VR"
SIZE"1B"
BODY_TYPE"PLUMBING"
HDL_POWER"GND";
"A\NAC"10;
%"CAP"
"1","(-775,1900)","2","mstr_discrete","I44";
;
CDS_SEC"1"
PART_NUMBER"A36096-104"
MATERIAL"X7R"
TOLERANCE"10%"
PACK_TYPE"0402"
VOLTAGE"16V"
VALUE"0.220UF"
LOCATION"C1G11"
ROOM"VDDQ_GHJ_PWR_VR"
CDS_LOCATION"C1G11"
SEC"1"
SEC_TYPE"0402"
SPOF"TRUE"
CDS_LIB"mstr_discrete";
"A"
$PN"1"44;
"B"
$PN"2"45;
%"CAP"
"1","(-2150,2500)","0","mstr_discrete","I45";
;
CDS_SEC"1"
TOLERANCE"10%"
MATERIAL"X6S"
PART_NUMBER"C95333-007"
LOCATION"C9U6"
VALUE"10UF"
PACK_TYPE"0805"
VOLTAGE"16V"
CDS_LIB"mstr_discrete"
ROOM"VDDQ_GHJ_PWR_VR"
CDS_LOCATION"C9U6"
SEC"1"
SEC_TYPE"0805";
"A"
$PN"1"19;
"B"
$PN"2"10;
%"CAP"
"1","(-1900,2500)","0","mstr_discrete","I46";
;
CDS_SEC"1"
MATERIAL"X6S"
TOLERANCE"10%"
VOLTAGE"16V"
LOCATION"C9U4"
PACK_TYPE"0805"
PART_NUMBER"C95333-007"
VALUE"10UF"
SEC_TYPE"0805"
SEC"1"
CDS_LOCATION"C9U4"
ROOM"VDDQ_GHJ_PWR_VR"
CDS_LIB"mstr_discrete";
"A"
$PN"1"19;
"B"
$PN"2"10;
%"CAP"
"1","(-1650,2500)","0","mstr_discrete","I47";
;
CDS_SEC"1"
TOLERANCE"10%"
PACK_TYPE"0805"
LOCATION"C9T4"
PART_NUMBER"C95333-007"
VALUE"10UF"
VOLTAGE"16V"
MATERIAL"X6S"
SEC_TYPE"0805"
ROOM"VDDQ_GHJ_PWR_VR"
CDS_LOCATION"C9T4"
SEC"1"
CDS_LIB"mstr_discrete";
"A"
$PN"1"19;
"B"
$PN"2"10;
%"CAP"
"1","(-1425,2500)","0","mstr_discrete","I48";
;
CDS_SEC"1"
CDS_LOCATION"C1F27"
VOLTAGE"16V"
MATERIAL"X6S"
PACK_TYPE"0402"
TOLERANCE"10%"
VALUE"1.0UF"
PART_NUMBER"D97712-011"
LOCATION"C1F27"
CDS_LIB"mstr_discrete"
SEC_TYPE"0402"
SEC"1"
ROOM"VDDQ_GHJ_PWR_VR";
"A"
$PN"1"19;
"B"
$PN"2"10;
%"CAP"
"1","(-925,2500)","0","mstr_discrete","I50";
;
CDS_SEC"1"
MATERIAL"X6S"
VOLTAGE"16V"
VALUE"1.0UF"
LOCATION"C1G6"
PACK_TYPE"0402"
PART_NUMBER"D97712-011"
TOLERANCE"10%"
SEC_TYPE"0402"
ROOM"VDDQ_GHJ_PWR_VR"
SEC"1"
CDS_LOCATION"C1G6"
CDS_LIB"mstr_discrete";
"A"
$PN"1"29;
"B"
$PN"2"10;
%"CAP_A"
"1","(-1175,2500)","0","dev_discrete","I51";
;
PACK_TYPE"0402V"
MATERIAL"X7R"
LOCATION"C1G14"
VALUE"0.1UF"
VOLTAGE"16V"
TOLERANCE"10%"
PART_NUMBER"A36096-030"
SEC"1"
SEC_TYPE"0402V"
CDS_SEC"1"
CDS_LOCATION"C1G14"
ROOM"VDDQ_GHJ_PWR_VR"
CDS_LIB"dev_discrete";
"B"
$PN"2"10;
"A"
$PN"1"19;
%"CAP"
"1","(25,2500)","0","mstr_discrete","I54";
;
CDS_SEC"1"
LOCATION"C1G5"
VALUE"0.22UF"
MATERIAL"X7R"
TOLERANCE"10%"
VOLTAGE"16V"
PACK_TYPE"0402"
PART_NUMBER"A36096-155"
CDS_LIB"mstr_discrete"
ROOM"VDDQ_GHJ_PWR_VR"
SEC_TYPE"0402"
SEC"1"
CDS_LOCATION"C1G5";
"A"
$PN"1"17;
"B"
$PN"2"10;
%"CAP"
"1","(4500,1800)","0","mstr_discrete","I6";
;
CDS_SEC"1"
MATERIAL"X6S"
LOCATION"C1G17"
VOLTAGE"4V"
VALUE"22UF"
GROUP"PWR_MLCC_CAP"
PART_NUMBER"C95333-002"
TOLERANCE"20%"
PACK_TYPE"0805LF"
SEC_TYPE"0805LF"
SEC"1"
BOM_COST"VDDQ_GHJ_PWR_VR"
ROOM"VDDQ_GHJ_PWR_VR"
CDS_LOCATION"C1G17"
CDS_LIB"mstr_discrete";
"A"
$PN"1"1;
"B"
$PN"2"13;
%"PVDDQ_GHJ"
"1","(4500,-325)","0","mstr_symbols","I64";
;
VOLTAGE"1.2V"
CDS_LIB"mstr_symbols"
BODY_TYPE"PLUMBING"
HDL_POWER"PVDDQ_GHJ";
"G\NAC"11;
%"CAP"
"1","(4500,-575)","0","mstr_discrete","I68";
;
CDS_SEC"1"
BOM_SS"NOPOP"
PACK_TYPE"0805LF"
PART_NUMBER"C95333-002"
VALUE"22UF"
VOLTAGE"4V"
GROUP"PWR_MLCC_CAP"
MATERIAL"X6S"
TOLERANCE"20%"
LOCATION"C1G20"
SEC_TYPE"0805LF"
SEC"1"
BOM_COST"VDDQ_GHJ_PWR_VR"
ROOM"VDDQ_GHJ_PWR_VR"
CDS_LOCATION"C1G20"
CDS_LIB"mstr_discrete";
"A"
$PN"1"11;
"B"
$PN"2"12;
%"GND"
"1","(4500,-750)","0","mstr_symbols","I69";
;
CDS_LIB"mstr_symbols"
VOLTAGE"0"
SIZE"1B"
BOM_COST"VDDQ_GHJ_PWR_VR"
ROOM"VDDQ_GHJ_PWR_VR"
BODY_TYPE"PLUMBING"
HDL_POWER"GND";
"A\NAC"12;
%"GND"
"1","(4500,1625)","0","mstr_symbols","I7";
;
BOM_COST"VDDQ_GHJ_PWR_VR"
VOLTAGE"0"
CDS_LIB"mstr_symbols"
SIZE"1B"
ROOM"VDDQ_GHJ_PWR_VR"
BODY_TYPE"PLUMBING"
HDL_POWER"GND";
"A\NAC"13;
%"GND"
"1","(2500,-925)","0","mstr_symbols","I70";
;
CDS_LIB"mstr_symbols"
SIZE"1B"
VOLTAGE"0"
BOM_COST"VDDQ_GHJ_PWR_VR"
ROOM"VDDQ_GHJ_PWR_VR"
BODY_TYPE"PLUMBING"
HDL_POWER"GND";
"A\NAC"14;
%"CAP"
"1","(100,150)","0","mstr_discrete","I72";
;
CDS_SEC"1"
CDS_LOCATION"C1G29"
BOM_SS"NOPOP"
TOLERANCE"10%"
PACK_TYPE"0402"
LOCATION"C1G29"
PART_NUMBER"A36096-155"
MATERIAL"X7R"
VOLTAGE"16V"
VALUE"0.22UF"
ROOM"VDDQ_GHJ_PWR_VR"
SEC"1"
SEC_TYPE"0402"
CDS_LIB"mstr_discrete";
"A"
$PN"1"18;
"B"
$PN"2"16;
%"CAP"
"1","(-625,-475)","2","mstr_discrete","I75";
;
CDS_SEC"1"
MATERIAL"X7R"
PART_NUMBER"A36096-104"
PACK_TYPE"0402"
BOM_SS"NOPOP"
TOLERANCE"10%"
VOLTAGE"16V"
LOCATION"C1F26"
VALUE"0.220UF"
CDS_LIB"mstr_discrete"
SPOF"TRUE"
SEC_TYPE"0402"
SEC"1"
CDS_LOCATION"C1F26"
ROOM"VDDQ_GHJ_PWR_VR";
"A"
$PN"1"39;
"B"
$PN"2"33;
%"CAP"
"1","(-800,125)","0","mstr_discrete","I77";
;
CDS_SEC"1"
CDS_LOCATION"C1G28"
BOM_SS"NOPOP"
MATERIAL"X6S"
VOLTAGE"16V"
PACK_TYPE"0402"
TOLERANCE"10%"
VALUE"1.0UF"
LOCATION"C1G28"
PART_NUMBER"D97712-011"
CDS_LIB"mstr_discrete"
ROOM"VDDQ_GHJ_PWR_VR"
SEC"1"
SEC_TYPE"0402";
"A"
$PN"1"21;
"B"
$PN"2"16;
%"CAP_A"
"1","(-1100,125)","0","dev_discrete","I78";
;
CDS_LOCATION"C1F28"
VOLTAGE"16V"
VALUE"0.1UF"
LOCATION"C1F28"
MATERIAL"X7R"
TOLERANCE"10%"
PACK_TYPE"0402V"
PART_NUMBER"A36096-030"
SEC"1"
SEC_TYPE"0402V"
CDS_SEC"1"
ROOM"VDDQ_GHJ_PWR_VR"
CDS_LIB"dev_discrete";
"B"
$PN"2"16;
"A"
$PN"1"15;
%"CAP"
"1","(-1375,125)","0","mstr_discrete","I79";
;
CDS_SEC"1"
TOLERANCE"10%"
MATERIAL"X6S"
PACK_TYPE"0402"
PART_NUMBER"D97712-011"
VOLTAGE"16V"
VALUE"1.0UF"
LOCATION"C1G13"
CDS_LIB"mstr_discrete"
CDS_LOCATION"C1G13"
ROOM"VDDQ_GHJ_PWR_VR"
SEC_TYPE"0402"
SEC"1";
"A"
$PN"1"15;
"B"
$PN"2"16;
%"CAP"
"1","(-1650,125)","0","mstr_discrete","I80";
;
CDS_SEC"1"
LOCATION"C9U3"
MATERIAL"X6S"
TOLERANCE"10%"
VOLTAGE"16V"
VALUE"10UF"
PACK_TYPE"0805"
PART_NUMBER"C95333-007"
CDS_LIB"mstr_discrete"
CDS_LOCATION"C9U3"
ROOM"VDDQ_GHJ_PWR_VR"
SEC_TYPE"0805"
SEC"1";
"A"
$PN"1"15;
"B"
$PN"2"16;
%"CAP"
"1","(-1925,125)","0","mstr_discrete","I81";
;
CDS_SEC"1"
TOLERANCE"10%"
MATERIAL"X6S"
PACK_TYPE"0805"
VOLTAGE"16V"
VALUE"10UF"
LOCATION"C9T6"
PART_NUMBER"C95333-007"
ROOM"VDDQ_GHJ_PWR_VR"
SEC"1"
SEC_TYPE"0805"
CDS_LOCATION"C9T6"
CDS_LIB"mstr_discrete";
"A"
$PN"1"15;
"B"
$PN"2"16;
%"VCC_CORE"
"1","(-2200,400)","0","mstr_symbols","I83";
;
HDL_POWER"VR_FET_SW_P12V_STBY_PVDDQ_GHJ"
CDS_LIB"mstr_symbols";
"A"15;
%"CAP"
"1","(-2200,125)","0","mstr_discrete","I84";
;
CDS_SEC"1"
CDS_LOCATION"C9T9"
VOLTAGE"16V"
MATERIAL"X6S"
VALUE"10UF"
TOLERANCE"10%"
LOCATION"C9T9"
PART_NUMBER"C95333-007"
PACK_TYPE"0805"
SEC"1"
SEC_TYPE"0805"
ROOM"VDDQ_GHJ_PWR_VR"
CDS_LIB"mstr_discrete";
"A"
$PN"1"15;
"B"
$PN"2"16;
%"GND"
"1","(-2200,-225)","0","mstr_symbols","I85";
;
HDL_POWER"GND"
BODY_TYPE"PLUMBING"
CDS_LIB"mstr_symbols"
VOLTAGE"0"
SIZE"1B"
BOM_COST"VDDQ_GHJ_PWR_VR"
ROOM"VDDQ_GHJ_PWR_VR";
"A\NAC"16;
%"P5V_STBY"
"1","(350,3150)","0","mstr_symbols","I87";
;
SIZE"1B"
CDS_LIB"mstr_symbols"
VOLTAGE"5.0V"
BODY_TYPE"PLUMBING"
HDL_POWER"P5V_STBY";
"G\NAC"17;
%"P5V_STBY"
"1","(550,800)","0","mstr_symbols","I88";
;
CDS_LIB"mstr_symbols"
SIZE"1B"
VOLTAGE"5.0V"
BODY_TYPE"PLUMBING"
HDL_POWER"P5V_STBY";
"G\NAC"18;
%"VCC_CORE"
"1","(-1700,2900)","0","mstr_symbols","I89";
;
HDL_POWER"VR_FET_SW_P12V_STBY_PVDDQ_GHJ"
CDS_LIB"mstr_symbols";
"A"19;
END.
